FILE_TYPE = CONNECTIVITY;
{Allegro Design Entry HDL 16.6-p007 (v16-6-112F) 10/10/2012}
"PAGE_NUMBER" = 64;
0"NC";
1"TP_P3E_CPU1_PE1_RSR3_TXN<15:8>";
2"TP_P3E_CPU1_PE1_MP_TXN<7:0>";
3"TP_P3E_CPU1_PE1_RSR3_TXP<15:8>";
4"TP_P3E_CPU1_PE1_MP_TXP<7:0>";
5"TP_P3E_CPU1_PE1_RSR3_RXN<15:8>";
6"TP_P3E_CPU1_PE1_MP_RXN<7:0>";
7"TP_P3E_CPU1_PE1_RSR3_RXP<15:8>";
8"TP_P3E_CPU1_PE1_MP_RXP<7:0>";
9"TP_P3E_CPU1_PE1_RSR3_TXN<14>";
10"TP_P3E_CPU1_PE1_RSR3_RXP<9>";
11"TP_P3E_CPU1_PE1_RSR3_RXP<11>";
12"TP_P3E_CPU1_PE1_RSR3_RXN<14>";
13"TP_P3E_CPU1_PE1_RSR3_RXP<10>";
14"TP_P3E_CPU1_PE1_MP_RXP<0>";
15"TP_P3E_CPU1_PE1_MP_RXP<1>";
16"TP_P3E_CPU1_PE1_MP_RXP<2>";
17"TP_P3E_CPU1_PE1_MP_RXP<3>";
18"TP_P3E_CPU1_PE1_MP_RXN<0>";
19"TP_P3E_CPU1_PE1_MP_RXN<1>";
20"TP_P3E_CPU1_PE1_MP_RXN<2>";
21"TP_P3E_CPU1_PE1_MP_RXN<3>";
22"TP_P3E_CPU1_PE1_MP_RXP<4>";
23"TP_P3E_CPU1_PE1_MP_RXP<5>";
24"TP_P3E_CPU1_PE1_MP_RXP<6>";
25"TP_P3E_CPU1_PE1_MP_RXP<7>";
26"TP_P3E_CPU1_PE1_RSR3_RXP<8>";
27"TP_P3E_CPU1_PE1_RSR3_RXP<12>";
28"TP_P3E_CPU1_PE1_RSR3_RXP<13>";
29"TP_P3E_CPU1_PE1_RSR3_RXP<14>";
30"TP_P3E_CPU1_PE1_RSR3_RXP<15>";
31"TP_P3E_CPU1_PE1_MP_RXN<4>";
32"TP_P3E_CPU1_PE1_MP_RXN<5>";
33"TP_P3E_CPU1_PE1_MP_RXN<6>";
34"TP_P3E_CPU1_PE1_MP_RXN<7>";
35"TP_P3E_CPU1_PE1_RSR3_RXN<8>";
36"TP_P3E_CPU1_PE1_RSR3_RXN<9>";
37"TP_P3E_CPU1_PE1_RSR3_RXN<10>";
38"TP_P3E_CPU1_PE1_RSR3_RXN<11>";
39"TP_P3E_CPU1_PE1_RSR3_RXN<12>";
40"TP_P3E_CPU1_PE1_RSR3_RXN<13>";
41"TP_P3E_CPU1_PE1_RSR3_RXN<15>";
42"TP_P3E_CPU1_PE1_MP_TXP<0>";
43"TP_P3E_CPU1_PE1_MP_TXP<1>";
44"TP_P3E_CPU1_PE1_MP_TXP<2>";
45"TP_P3E_CPU1_PE1_MP_TXP<3>";
46"TP_P3E_CPU1_PE1_MP_TXN<0>";
47"TP_P3E_CPU1_PE1_MP_TXN<1>";
48"TP_P3E_CPU1_PE1_MP_TXN<2>";
49"TP_P3E_CPU1_PE1_MP_TXN<3>";
50"TP_P3E_CPU1_PE1_MP_TXP<4>";
51"TP_P3E_CPU1_PE1_MP_TXP<5>";
52"TP_P3E_CPU1_PE1_MP_TXP<6>";
53"TP_P3E_CPU1_PE1_MP_TXP<7>";
54"TP_P3E_CPU1_PE1_RSR3_TXP<8>";
55"TP_P3E_CPU1_PE1_RSR3_TXP<9>";
56"TP_P3E_CPU1_PE1_RSR3_TXP<10>";
57"TP_P3E_CPU1_PE1_RSR3_TXP<11>";
58"TP_P3E_CPU1_PE1_RSR3_TXP<12>";
59"TP_P3E_CPU1_PE1_RSR3_TXP<13>";
60"TP_P3E_CPU1_PE1_RSR3_TXP<14>";
61"TP_P3E_CPU1_PE1_RSR3_TXP<15>";
62"TP_P3E_CPU1_PE1_MP_TXN<4>";
63"TP_P3E_CPU1_PE1_MP_TXN<5>";
64"TP_P3E_CPU1_PE1_MP_TXN<6>";
65"TP_P3E_CPU1_PE1_MP_TXN<7>";
66"TP_P3E_CPU1_PE1_RSR3_TXN<8>";
67"TP_P3E_CPU1_PE1_RSR3_TXN<9>";
68"TP_P3E_CPU1_PE1_RSR3_TXN<10>";
69"TP_P3E_CPU1_PE1_RSR3_TXN<11>";
70"TP_P3E_CPU1_PE1_RSR3_TXN<12>";
71"TP_P3E_CPU1_PE1_RSR3_TXN<13>";
72"TP_P3E_CPU1_PE1_RSR3_TXN<15>";
%"TAP"
"1","(-5500,2125)","2","mstr_standard","I10";
;
CDS_LIB"mstr_standard"
BODY_TYPE"PLUMBING"
HDL_TAP"TRUE";
"B \NAC \NWC"6;
"S \NAC"
BN"4"31;
%"TAP"
"1","(-5500,2175)","2","mstr_standard","I11";
;
CDS_LIB"mstr_standard"
BODY_TYPE"PLUMBING"
HDL_TAP"TRUE";
"B \NAC \NWC"6;
"S \NAC"
BN"5"32;
%"TAP"
"1","(-5500,2275)","2","mstr_standard","I12";
;
CDS_LIB"mstr_standard"
BODY_TYPE"PLUMBING"
HDL_TAP"TRUE";
"B \NAC \NWC"6;
"S \NAC"
BN"7"34;
%"TAP"
"1","(-5500,2225)","2","mstr_standard","I13";
;
CDS_LIB"mstr_standard"
BODY_TYPE"PLUMBING"
HDL_TAP"TRUE";
"B \NAC \NWC"6;
"S \NAC"
BN"6"33;
%"TAP"
"1","(-5350,1975)","2","mstr_standard","I14";
;
CDS_LIB"mstr_standard"
BODY_TYPE"PLUMBING"
HDL_TAP"TRUE";
"B \NAC \NWC"8;
"S \NAC"
BN"2"16;
%"TAP"
"1","(-5350,2025)","2","mstr_standard","I15";
;
CDS_LIB"mstr_standard"
BODY_TYPE"PLUMBING"
HDL_TAP"TRUE";
"B \NAC \NWC"8;
"S \NAC"
BN"3"17;
%"TAP"
"1","(-5350,2425)","2","mstr_standard","I16";
;
CDS_LIB"mstr_standard"
BODY_TYPE"PLUMBING"
HDL_TAP"TRUE";
"B \NAC \NWC"8;
"S \NAC"
BN"5"23;
%"TAP"
"1","(-5350,2375)","2","mstr_standard","I17";
;
CDS_LIB"mstr_standard"
BODY_TYPE"PLUMBING"
HDL_TAP"TRUE";
"B \NAC \NWC"8;
"S \NAC"
BN"4"22;
%"TAP"
"1","(-5350,2475)","2","mstr_standard","I18";
;
CDS_LIB"mstr_standard"
BODY_TYPE"PLUMBING"
HDL_TAP"TRUE";
"B \NAC \NWC"8;
"S \NAC"
BN"6"24;
%"TAP"
"1","(-5500,2625)","2","mstr_standard","I19";
;
CDS_LIB"mstr_standard"
BODY_TYPE"PLUMBING"
HDL_TAP"TRUE";
"B \NAC \NWC"5;
"S \NAC"
BN"8"35;
%"TAP"
"1","(-5500,2675)","2","mstr_standard","I20";
;
CDS_LIB"mstr_standard"
BODY_TYPE"PLUMBING"
HDL_TAP"TRUE";
"B \NAC \NWC"5;
"S \NAC"
BN"9"36;
%"TAP"
"1","(-5500,2725)","2","mstr_standard","I21";
;
CDS_LIB"mstr_standard"
BODY_TYPE"PLUMBING"
HDL_TAP"TRUE";
"B \NAC \NWC"5;
"S \NAC"
BN"10"37;
%"TAP"
"1","(-5500,2775)","2","mstr_standard","I22";
;
CDS_LIB"mstr_standard"
BODY_TYPE"PLUMBING"
HDL_TAP"TRUE";
"B \NAC \NWC"5;
"S \NAC"
BN"11"38;
%"TAP"
"1","(-5350,2525)","2","mstr_standard","I23";
;
CDS_LIB"mstr_standard"
BODY_TYPE"PLUMBING"
HDL_TAP"TRUE";
"B \NAC \NWC"8;
"S \NAC"
BN"7"25;
%"TAP"
"1","(-5350,2875)","2","mstr_standard","I24";
;
CDS_LIB"mstr_standard"
BODY_TYPE"PLUMBING"
HDL_TAP"TRUE";
"B \NAC \NWC"7;
"S \NAC"
BN"8"26;
%"TAP"
"1","(-5350,2925)","2","mstr_standard","I25";
;
CDS_LIB"mstr_standard"
BODY_TYPE"PLUMBING"
HDL_TAP"TRUE";
"B \NAC \NWC"7;
"S \NAC"
BN"9"10;
%"TAP"
"1","(-5350,2975)","2","mstr_standard","I26";
;
CDS_LIB"mstr_standard"
BODY_TYPE"PLUMBING"
HDL_TAP"TRUE";
"B \NAC \NWC"7;
"S \NAC"
BN"10"13;
%"TAP"
"1","(-5500,3225)","2","mstr_standard","I27";
;
CDS_LIB"mstr_standard"
BODY_TYPE"PLUMBING"
HDL_TAP"TRUE";
"B \NAC \NWC"5;
"S \NAC"
BN"14"12;
%"TAP"
"1","(-5500,3175)","2","mstr_standard","I28";
;
CDS_LIB"mstr_standard"
BODY_TYPE"PLUMBING"
HDL_TAP"TRUE";
"B \NAC \NWC"5;
"S \NAC"
BN"13"40;
%"TAP"
"1","(-5500,3125)","2","mstr_standard","I29";
;
CDS_LIB"mstr_standard"
BODY_TYPE"PLUMBING"
HDL_TAP"TRUE";
"B \NAC \NWC"5;
"S \NAC"
BN"12"39;
%"TAP"
"1","(-5500,1625)","2","mstr_standard","I3";
;
CDS_LIB"mstr_standard"
BODY_TYPE"PLUMBING"
HDL_TAP"TRUE";
"B \NAC \NWC"6;
"S \NAC"
BN"0"18;
%"TAP"
"1","(-5500,3275)","2","mstr_standard","I30";
;
CDS_LIB"mstr_standard"
BODY_TYPE"PLUMBING"
HDL_TAP"TRUE";
"B \NAC \NWC"5;
"S \NAC"
BN"15"41;
%"TAP"
"1","(-5350,3025)","2","mstr_standard","I31";
;
CDS_LIB"mstr_standard"
BODY_TYPE"PLUMBING"
HDL_TAP"TRUE";
"B \NAC \NWC"7;
"S \NAC"
BN"11"11;
%"TAP"
"1","(-5350,3375)","2","mstr_standard","I32";
;
CDS_LIB"mstr_standard"
BODY_TYPE"PLUMBING"
HDL_TAP"TRUE";
"B \NAC \NWC"7;
"S \NAC"
BN"12"27;
%"TAP"
"1","(-5350,3425)","2","mstr_standard","I33";
;
CDS_LIB"mstr_standard"
BODY_TYPE"PLUMBING"
HDL_TAP"TRUE";
"B \NAC \NWC"7;
"S \NAC"
BN"13"28;
%"TAP"
"1","(-5350,3475)","2","mstr_standard","I34";
;
CDS_LIB"mstr_standard"
BODY_TYPE"PLUMBING"
HDL_TAP"TRUE";
"B \NAC \NWC"7;
"S \NAC"
BN"14"29;
%"TAP"
"1","(-5350,3525)","2","mstr_standard","I35";
;
CDS_LIB"mstr_standard"
BODY_TYPE"PLUMBING"
HDL_TAP"TRUE";
"B \NAC \NWC"7;
"S \NAC"
BN"15"30;
%"TAP"
"1","(-2725,1625)","0","mstr_standard","I36";
;
CDS_LIB"mstr_standard"
BODY_TYPE"PLUMBING"
HDL_TAP"TRUE";
"B \NAC \NWC"2;
"S \NAC"
BN"0"46;
%"TAP"
"1","(-2725,1675)","0","mstr_standard","I37";
;
CDS_LIB"mstr_standard"
BODY_TYPE"PLUMBING"
HDL_TAP"TRUE";
"B \NAC \NWC"2;
"S \NAC"
BN"1"47;
%"TAP"
"1","(-2875,1925)","0","mstr_standard","I38";
;
CDS_LIB"mstr_standard"
BODY_TYPE"PLUMBING"
HDL_TAP"TRUE";
"B \NAC \NWC"4;
"S \NAC"
BN"1"43;
%"TAP"
"1","(-2875,1875)","0","mstr_standard","I39";
;
CDS_LIB"mstr_standard"
BODY_TYPE"PLUMBING"
HDL_TAP"TRUE";
"B \NAC \NWC"4;
"S \NAC"
BN"0"42;
%"TAP"
"1","(-5500,1675)","2","mstr_standard","I4";
;
CDS_LIB"mstr_standard"
BODY_TYPE"PLUMBING"
HDL_TAP"TRUE";
"B \NAC \NWC"6;
"S \NAC"
BN"1"19;
%"TAP"
"1","(-2725,1775)","0","mstr_standard","I40";
;
CDS_LIB"mstr_standard"
BODY_TYPE"PLUMBING"
HDL_TAP"TRUE";
"B \NAC \NWC"2;
"S \NAC"
BN"3"49;
%"TAP"
"1","(-2725,1725)","0","mstr_standard","I41";
;
CDS_LIB"mstr_standard"
BODY_TYPE"PLUMBING"
HDL_TAP"TRUE";
"B \NAC \NWC"2;
"S \NAC"
BN"2"48;
%"TAP"
"1","(-2875,2025)","0","mstr_standard","I42";
;
CDS_LIB"mstr_standard"
BODY_TYPE"PLUMBING"
HDL_TAP"TRUE";
"B \NAC \NWC"4;
"S \NAC"
BN"3"45;
%"TAP"
"1","(-2875,1975)","0","mstr_standard","I43";
;
CDS_LIB"mstr_standard"
BODY_TYPE"PLUMBING"
HDL_TAP"TRUE";
"B \NAC \NWC"4;
"S \NAC"
BN"2"44;
%"TAP"
"1","(-2725,2125)","0","mstr_standard","I44";
;
CDS_LIB"mstr_standard"
BODY_TYPE"PLUMBING"
HDL_TAP"TRUE";
"B \NAC \NWC"2;
"S \NAC"
BN"4"62;
%"TAP"
"1","(-2725,2175)","0","mstr_standard","I45";
;
CDS_LIB"mstr_standard"
BODY_TYPE"PLUMBING"
HDL_TAP"TRUE";
"B \NAC \NWC"2;
"S \NAC"
BN"5"63;
%"TAP"
"1","(-2725,2225)","0","mstr_standard","I46";
;
CDS_LIB"mstr_standard"
BODY_TYPE"PLUMBING"
HDL_TAP"TRUE";
"B \NAC \NWC"2;
"S \NAC"
BN"6"64;
%"TAP"
"1","(-2875,2375)","0","mstr_standard","I47";
;
CDS_LIB"mstr_standard"
BODY_TYPE"PLUMBING"
HDL_TAP"TRUE";
"B \NAC \NWC"4;
"S \NAC"
BN"4"50;
%"TAP"
"1","(-2875,2425)","0","mstr_standard","I48";
;
CDS_LIB"mstr_standard"
BODY_TYPE"PLUMBING"
HDL_TAP"TRUE";
"B \NAC \NWC"4;
"S \NAC"
BN"5"51;
%"TAP"
"1","(-2875,2475)","0","mstr_standard","I49";
;
CDS_LIB"mstr_standard"
BODY_TYPE"PLUMBING"
HDL_TAP"TRUE";
"B \NAC \NWC"4;
"S \NAC"
BN"6"52;
%"TAP"
"1","(-5500,1725)","2","mstr_standard","I5";
;
CDS_LIB"mstr_standard"
BODY_TYPE"PLUMBING"
HDL_TAP"TRUE";
"B \NAC \NWC"6;
"S \NAC"
BN"2"20;
%"TAP"
"1","(-2725,2275)","0","mstr_standard","I50";
;
CDS_LIB"mstr_standard"
BODY_TYPE"PLUMBING"
HDL_TAP"TRUE";
"B \NAC \NWC"2;
"S \NAC"
BN"7"65;
%"TAP"
"1","(-2875,2525)","0","mstr_standard","I51";
;
CDS_LIB"mstr_standard"
BODY_TYPE"PLUMBING"
HDL_TAP"TRUE";
"B \NAC \NWC"4;
"S \NAC"
BN"7"53;
%"TAP"
"1","(-2725,2625)","0","mstr_standard","I52";
;
CDS_LIB"mstr_standard"
BODY_TYPE"PLUMBING"
HDL_TAP"TRUE";
"B \NAC \NWC"1;
"S \NAC"
BN"8"66;
%"TAP"
"1","(-2725,2725)","0","mstr_standard","I53";
;
CDS_LIB"mstr_standard"
BODY_TYPE"PLUMBING"
HDL_TAP"TRUE";
"B \NAC \NWC"1;
"S \NAC"
BN"10"68;
%"TAP"
"1","(-2725,2675)","0","mstr_standard","I54";
;
CDS_LIB"mstr_standard"
BODY_TYPE"PLUMBING"
HDL_TAP"TRUE";
"B \NAC \NWC"1;
"S \NAC"
BN"9"67;
%"TAP"
"1","(-2875,2875)","0","mstr_standard","I55";
;
CDS_LIB"mstr_standard"
BODY_TYPE"PLUMBING"
HDL_TAP"TRUE";
"B \NAC \NWC"3;
"S \NAC"
BN"8"54;
%"TAP"
"1","(-2875,2925)","0","mstr_standard","I56";
;
CDS_LIB"mstr_standard"
BODY_TYPE"PLUMBING"
HDL_TAP"TRUE";
"B \NAC \NWC"3;
"S \NAC"
BN"9"55;
%"TAP"
"1","(-2875,2975)","0","mstr_standard","I57";
;
CDS_LIB"mstr_standard"
BODY_TYPE"PLUMBING"
HDL_TAP"TRUE";
"B \NAC \NWC"3;
"S \NAC"
BN"10"56;
%"TAP"
"1","(-2725,2775)","0","mstr_standard","I58";
;
CDS_LIB"mstr_standard"
BODY_TYPE"PLUMBING"
HDL_TAP"TRUE";
"B \NAC \NWC"1;
"S \NAC"
BN"11"69;
%"TAP"
"1","(-2875,3025)","0","mstr_standard","I59";
;
CDS_LIB"mstr_standard"
BODY_TYPE"PLUMBING"
HDL_TAP"TRUE";
"B \NAC \NWC"3;
"S \NAC"
BN"11"57;
%"TAP"
"1","(-5500,1775)","2","mstr_standard","I6";
;
CDS_LIB"mstr_standard"
BODY_TYPE"PLUMBING"
HDL_TAP"TRUE";
"B \NAC \NWC"6;
"S \NAC"
BN"3"21;
%"TAP"
"1","(-2725,3125)","0","mstr_standard","I60";
;
CDS_LIB"mstr_standard"
BODY_TYPE"PLUMBING"
HDL_TAP"TRUE";
"B \NAC \NWC"1;
"S \NAC"
BN"12"70;
%"TAP"
"1","(-2725,3175)","0","mstr_standard","I61";
;
CDS_LIB"mstr_standard"
BODY_TYPE"PLUMBING"
HDL_TAP"TRUE";
"B \NAC \NWC"1;
"S \NAC"
BN"13"71;
%"TAP"
"1","(-2725,3225)","0","mstr_standard","I62";
;
CDS_LIB"mstr_standard"
BODY_TYPE"PLUMBING"
HDL_TAP"TRUE";
"B \NAC \NWC"1;
"S \NAC"
BN"14"9;
%"TAP"
"1","(-2875,3375)","0","mstr_standard","I63";
;
CDS_LIB"mstr_standard"
BODY_TYPE"PLUMBING"
HDL_TAP"TRUE";
"B \NAC \NWC"3;
"S \NAC"
BN"12"58;
%"TAP"
"1","(-2875,3425)","0","mstr_standard","I64";
;
CDS_LIB"mstr_standard"
BODY_TYPE"PLUMBING"
HDL_TAP"TRUE";
"B \NAC \NWC"3;
"S \NAC"
BN"13"59;
%"TAP"
"1","(-2875,3475)","0","mstr_standard","I65";
;
CDS_LIB"mstr_standard"
BODY_TYPE"PLUMBING"
HDL_TAP"TRUE";
"B \NAC \NWC"3;
"S \NAC"
BN"14"60;
%"TAP"
"1","(-2725,3275)","0","mstr_standard","I66";
;
CDS_LIB"mstr_standard"
BODY_TYPE"PLUMBING"
HDL_TAP"TRUE";
"B \NAC \NWC"1;
"S \NAC"
BN"15"72;
%"TAP"
"1","(-2875,3525)","0","mstr_standard","I67";
;
CDS_LIB"mstr_standard"
BODY_TYPE"PLUMBING"
HDL_TAP"TRUE";
"B \NAC \NWC"3;
"S \NAC"
BN"15"61;
%"SKX_EXT_B"
"10","(-4075,2575)","0","chpset_lib","I68";
;
CDS_SEC"10"
LOCATION"U2D1"
PART_NUMBER"TBD"
MATERIAL"IC"
PACK_TYPE"BGA1"
SEC_TYPE"BGA1"
CDS_LIB"chpset_lib"
SEC"10"
CDS_LOCATION"U2D1";
"PE1_TX_DP<0>"
$PN"CW2"42;
"PE1_TX_DP<1>"
$PN"DB1"43;
"PE1_TX_DP<2>"
$PN"DD3"44;
"PE1_TX_DP<3>"
$PN"DC4"45;
"PE1_TX_DP<4>"
$PN"DF3"50;
"PE1_TX_DP<5>"
$PN"DH3"51;
"PE1_TX_DP<6>"
$PN"DL2"52;
"PE1_TX_DP<7>"
$PN"DP3"53;
"PE1_TX_DP<8>"
$PN"DR4"54;
"PE1_TX_DP<9>"
$PN"DU2"55;
"PE1_TX_DP<10>"
$PN"DU4"56;
"PE1_TX_DP<11>"
$PN"DV5"57;
"PE1_TX_DP<12>"
$PN"DT7"58;
"PE1_TX_DP<13>"
$PN"DW6"59;
"PE1_TX_DP<14>"
$PN"EB7"60;
"PE1_TX_DP<15>"
$PN"EC8"61;
"PE1_TX_DN<0>"
$PN"DA2"46;
"PE1_TX_DN<1>"
$PN"DC2"47;
"PE1_TX_DN<2>"
$PN"DE2"48;
"PE1_TX_DN<3>"
$PN"DE4"49;
"PE1_TX_DN<4>"
$PN"DG4"62;
"PE1_TX_DN<5>"
$PN"DK3"63;
"PE1_TX_DN<6>"
$PN"DM3"64;
"PE1_TX_DN<7>"
$PN"DN4"65;
"PE1_TX_DN<8>"
$PN"DT5"66;
"PE1_TX_DN<9>"
$PN"DV3"67;
"PE1_TX_DN<10>"
$PN"DW4"68;
"PE1_TX_DN<11>"
$PN"DU6"69;
"PE1_TX_DN<12>"
$PN"DV7"70;
"PE1_TX_DN<13>"
$PN"DY7"71;
"PE1_TX_DN<14>"
$PN"EA8"9;
"PE1_TX_DN<15>"
$PN"ED9"72;
"PE1_RX_DP<0>"
$PN"CU8"14;
"PE1_RX_DP<1>"
$PN"CY7"15;
"PE1_RX_DP<2>"
$PN"DB9"16;
"PE1_RX_DP<3>"
$PN"DA10"17;
"PE1_RX_DP<4>"
$PN"DD9"22;
"PE1_RX_DP<5>"
$PN"DF9"23;
"PE1_RX_DP<6>"
$PN"DJ8"24;
"PE1_RX_DP<7>"
$PN"DL10"25;
"PE1_RX_DP<8>"
$PN"DK11"26;
"PE1_RX_DP<9>"
$PN"DN10"10;
"PE1_RX_DP<10>"
$PN"DR12"13;
"PE1_RX_DP<11>"
$PN"DP13"11;
"PE1_RX_DP<12>"
$PN"DU12"27;
"PE1_RX_DP<13>"
$PN"DY13"28;
"PE1_RX_DP<14>"
$PN"DV15"29;
"PE1_RX_DP<15>"
$PN"DT15"30;
"PE1_RX_DN<0>"
$PN"CW8"18;
"PE1_RX_DN<1>"
$PN"DA8"19;
"PE1_RX_DN<2>"
$PN"DC8"20;
"PE1_RX_DN<3>"
$PN"DC10"21;
"PE1_RX_DN<4>"
$PN"DE10"31;
"PE1_RX_DN<5>"
$PN"DH9"32;
"PE1_RX_DN<6>"
$PN"DK9"33;
"PE1_RX_DN<7>"
$PN"DM9"34;
"PE1_RX_DN<8>"
$PN"DM11"35;
"PE1_RX_DN<9>"
$PN"DP11"36;
"PE1_RX_DN<10>"
$PN"DT11"37;
"PE1_RX_DN<11>"
$PN"DT13"38;
"PE1_RX_DN<12>"
$PN"DV13"39;
"PE1_RX_DN<13>"
$PN"DW14"40;
"PE1_RX_DN<14>"
$PN"DY15"12;
"PE1_RX_DN<15>"
$PN"DU16"41;
%"TAP"
"1","(-5350,1875)","2","mstr_standard","I7";
;
CDS_LIB"mstr_standard"
BODY_TYPE"PLUMBING"
HDL_TAP"TRUE";
"B \NAC \NWC"8;
"S \NAC"
BN"0"14;
%"TAP"
"1","(-5350,1925)","2","mstr_standard","I8";
;
CDS_LIB"mstr_standard"
BODY_TYPE"PLUMBING"
HDL_TAP"TRUE";
"B \NAC \NWC"8;
"S \NAC"
BN"1"15;
END.
